G04 ================== begin FILE IDENTIFICATION RECORD ==================*
G04 Layout Name:  17301-sa.brd*
G04 Film Name:    L4*
G04 File Format:  Gerber RS274X*
G04 File Origin:  Cadence Allegro 16.6-2015-S079*
G04 Origin Date:  Thu Jun 22 17:50:03 2017*
G04 *
G04 Layer:  VIA CLASS/L4*
G04 Layer:  PIN/L4*
G04 Layer:  ETCH/L4*
G04 Layer:  DRAWING FORMAT/LAYER_PCB_STORY*
G04 Layer:  DRAWING FORMAT/LAYER_L4*
G04 *
G04 Offset:    (0.00 0.00)*
G04 Mirror:    No*
G04 Mode:      Positive*
G04 Rotation:  0*
G04 FullContactRelief:  No*
G04 UndefLineWidth:     6.00*
G04 ================== end FILE IDENTIFICATION RECORD ====================*
%FSLAX35Y35*MOIN*%
%IR0*IPPOS*OFA0.00000B0.00000*MIA0B0*SFA1.00000B1.00000*%
%ADD14C,.02*%
%ADD12C,.022*%
%ADD13C,.034*%
%ADD16C,.071*%
%ADD15O,.024X.032*%
%ADD11C,.146*%
%ADD10C,.182*%
%ADD17C,.006*%
%ADD21C,.04404*%
%ADD22C,.07204*%
%ADD20C,.04604*%
%ADD23C,.09504*%
%ADD18C,.11004*%
%ADD19C,.11704*%
G75*
%LPD*%
G75*
G36*
G01X142644Y67411D02*
X177083D01*
X186771Y57723D01*
G02X186692Y56952I-354J-353D01*
G03X186154Y56496I1593J-2425D01*
G02X185420I-367J339D01*
G03X181154I-2133J-1968D01*
G02X180420I-367J339D01*
G03X176154I-2133J-1968D01*
G02X175420I-367J339D01*
G03X171154I-2133J-1968D01*
G02X170420I-367J339D01*
G03X166154I-2133J-1968D01*
G02X165420I-367J339D01*
G03X161154I-2133J-1968D01*
G02X160420I-367J339D01*
G03X156154I-2133J-1968D01*
G02X155420I-367J339D01*
G03X151154I-2133J-1968D01*
G02X150420I-367J339D01*
G03X146154I-2133J-1968D01*
G02X145420I-367J339D01*
G03Y52560I-2133J-1968D01*
G02X146154I367J-339D01*
G03X150420I2133J1968D01*
G02X151154I367J-339D01*
G03X155420I2133J1968D01*
G02X156154I367J-339D01*
G03X160420I2133J1968D01*
G02X161154I367J-339D01*
G03X165420I2133J1968D01*
G02X166154I367J-339D01*
G03X170420I2133J1968D01*
G02X171154I367J-339D01*
G03X175420I2133J1968D01*
G02X176154I367J-339D01*
G03X180420I2133J1968D01*
G02X181154I367J-339D01*
G03X185420I2133J1968D01*
G02X186154I367J-339D01*
G03X190420I2133J1968D01*
G02X191154I367J-339D01*
G03X195420I2133J1968D01*
G02X196154I367J-339D01*
G03X200420I2133J1968D01*
G02X201154I367J-339D01*
G03X202278Y51807I2133J1968D01*
G01Y12760D01*
G03X201154Y12007I1009J-2721D01*
G02X200420I-367J339D01*
G03X196154I-2133J-1968D01*
G02X195420I-367J339D01*
G03X191154I-2133J-1968D01*
G02X190420I-367J339D01*
G03X186154I-2133J-1968D01*
G02X185420I-367J339D01*
G03X181154I-2133J-1968D01*
G02X180420I-367J339D01*
G03X176154I-2133J-1968D01*
G02X175420I-367J339D01*
G03X171154I-2133J-1968D01*
G02X170420I-367J339D01*
G03X166154I-2133J-1968D01*
G02X165420I-367J339D01*
G03X161154I-2133J-1968D01*
G02X160420I-367J339D01*
G03X156154I-2133J-1968D01*
G02X155420I-367J339D01*
G03X151154I-2133J-1968D01*
G02X150420I-367J339D01*
G03X146154I-2133J-1968D01*
G02X145420I-367J339D01*
G03Y8071I-2133J-1968D01*
G02X146154I367J-339D01*
G03X150420I2133J1968D01*
G02X151154I367J-339D01*
G03X155420I2133J1968D01*
G02X156154I367J-339D01*
G03X160420I2133J1968D01*
G02X161154I367J-339D01*
G03X165420I2133J1968D01*
G02X166154I367J-339D01*
G03X170420I2133J1968D01*
G02X171154I367J-339D01*
G03X175420I2133J1968D01*
G02X176154I367J-339D01*
G03X180420I2133J1968D01*
G02X181154I367J-339D01*
G03X185420I2133J1968D01*
G02X186154I367J-339D01*
G03X190420I2133J1968D01*
G02X191154I367J-339D01*
G03X195420I2133J1968D01*
G02X196154I367J-339D01*
G03X200420I2133J1968D01*
G02X201154I367J-339D01*
G03X202278Y7318I2133J1968D01*
G01Y6288D01*
X73567D01*
G03X71417Y3612I0J-2202D01*
G02X70929Y3004I-488J-108D01*
G01X3937D01*
G02X3004Y3937I0J933D01*
G01Y87402D01*
G02X3937Y88335I933J0D01*
G01X47340D01*
X47905Y87770D01*
Y68548D01*
X49042Y67411D01*
X74471D01*
X74531Y67247D01*
G03X78669I2069J753D01*
G01X78729Y67411D01*
X118930D01*
X118962Y67198D01*
G03X122912Y65740I2375J355D01*
G03X126062I1575J1813D01*
G03X129212I1575J1813D01*
G03X132362I1575J1813D01*
G03X135512I1575J1813D01*
G03X138662I1575J1813D01*
G03X142612Y67198I1575J1813D01*
G01X142644Y67411D01*
G37*
G36*
G01X265800Y46600D02*
X264300Y48100D01*
Y53400D01*
X262600Y55100D01*
X251000D01*
X242600Y63500D01*
X237760D01*
G03X229164I-4298J-3972D01*
G01X224900D01*
X224766Y63366D01*
X224679Y63357D01*
G03X221677Y61300I418J-3829D01*
G01X187220D01*
X180000Y68520D01*
X177673D01*
X177581Y68612D01*
X142633D01*
X142594Y68814D01*
G03X138662Y70166I-2357J-461D01*
G03X135512I-1575J-1813D01*
G03X132362I-1575J-1813D01*
G03X129212I-1575J-1813D01*
G03X126062I-1575J-1813D01*
G03X122912I-1575J-1813D01*
G03X118980Y68814I-1575J-1813D01*
G01X118941Y68612D01*
X78722D01*
X78661Y68775D01*
G03X74539I-2061J-775D01*
G01X74478Y68612D01*
X51016D01*
X49716Y69913D01*
Y86676D01*
X51378Y88338D01*
X65997D01*
G02X66347Y87481I0J-500D01*
G03X69573I1613J-1642D01*
G02X69923Y88338I350J357D01*
G01X85997D01*
G02X86347Y87481I0J-500D01*
G03X89573I1613J-1642D01*
G02X89923Y88338I350J357D01*
G01X105997D01*
G02X106347Y87481I0J-500D01*
G03X109573I1613J-1642D01*
G02X109923Y88338I350J357D01*
G01X125997D01*
G02X126347Y87481I0J-500D01*
G03X129573I1613J-1642D01*
G02X129923Y88338I350J357D01*
G01X145997D01*
G02X146347Y87481I0J-500D01*
G03X149573I1613J-1642D01*
G02X149923Y88338I350J357D01*
G01X165997D01*
G02X166347Y87481I0J-500D01*
G03X169573I1613J-1642D01*
G02X169923Y88338I350J357D01*
G01X185997D01*
G02X186347Y87481I0J-500D01*
G03X189573I1613J-1642D01*
G02X189923Y88338I350J357D01*
G01X192914D01*
G03X197883Y93307I-1J4970D01*
G01Y94243D01*
X269685D01*
G03X276623Y101181I0J6938D01*
G01Y172250D01*
G02X277480Y172600I500J0D01*
G03Y175826I1642J1613D01*
G02X276623Y176176I-357J350D01*
G01Y192250D01*
G02X277480Y192600I500J0D01*
G03Y195826I1642J1613D01*
G02X276623Y196176I-357J350D01*
G01Y212250D01*
G02X277480Y212600I500J0D01*
G03Y215826I1642J1613D01*
G02X276623Y216176I-357J350D01*
G01Y225530D01*
X282595Y231502D01*
X317770D01*
X334440Y248172D01*
X537525D01*
X541029Y244668D01*
X541009Y244542D01*
G03X552810Y232741I10172J-1629D01*
G01X552936Y232761D01*
X555241Y230456D01*
Y106183D01*
X531837Y82778D01*
X531752Y82768D01*
G03X528531Y79547I453J-3674D01*
G01X528521Y79462D01*
X527699Y78640D01*
X477525D01*
X476845Y79320D01*
X476837Y79411D01*
G03X472801Y82779I-3688J-317D01*
G01X472789Y82778D01*
X471057D01*
X468949Y84886D01*
Y91380D01*
G02X469805Y91730I500J-1D01*
G03X469771Y94926I1640J1616D01*
G02X468911Y95217I-363J344D01*
G03X462008Y101429I-6903J-729D01*
G01X377149D01*
X366769Y111809D01*
X349088D01*
X344707Y107428D01*
Y92128D01*
G03X343445Y89990I935J-1994D01*
G02X342962Y89457I-499J-33D01*
G03X341016Y87448I66J-2010D01*
G01Y83447D01*
G03X341058Y83041I2012J3D01*
G02X340673Y82451I-490J-101D01*
G03X339316Y81542I460J-2153D01*
G02X338626Y81408I-413J282D01*
G03X339223Y78331I-1220J-1833D01*
G02X339913Y78465I413J-282D01*
G03X343251Y80900I1220J1833D01*
G02X343592Y81516I481J136D01*
G03X343972Y81671I-566J1930D01*
G02X344707Y81229I235J-441D01*
G01Y74048D01*
X341776Y71117D01*
Y65146D01*
X338411Y61781D01*
X334939D01*
G02X334640Y62682I0J500D01*
G03X332490Y69172I-2150J2889D01*
G01X328690D01*
G03X326540Y62682I0J-3601D01*
G02X326241Y61781I-299J-401D01*
G01X300814D01*
X285633Y46600D01*
X265800D01*
G37*
G36*
G01X222492Y3795D02*
G03X220310Y6288I-2182J292D01*
G01X204616D01*
Y7459D01*
G03X205420Y8071I-1329J2580D01*
G02X206154I367J-339D01*
G03X210420I2133J1968D01*
G02X211154I367J-339D01*
G03Y12007I2133J1968D01*
G02X210420I-367J339D01*
G03X206154I-2133J-1968D01*
G02X205420I-367J339D01*
G03X204616Y12619I-2133J-1968D01*
G01Y51948D01*
G03X205420Y52560I-1329J2580D01*
G02X206154I367J-339D01*
G03X210420I2133J1968D01*
G02X211154I367J-339D01*
G03Y56496I2133J1968D01*
G02X210420I-367J339D01*
G03X206154I-2133J-1968D01*
G02X205420I-367J339D01*
G03X204616Y57108I-2133J-1968D01*
G01Y57958D01*
X206579Y59921D01*
X220747D01*
G02X221247Y59433I0J-500D01*
G03X227680Y56671I3850J95D01*
G02X228422Y56554I320J-385D01*
G03X239312Y59388I5040J2974D01*
G01X239318Y59632D01*
X242768D01*
X257000Y45400D01*
X265301D01*
X265302Y45398D01*
X286131D01*
X286132Y45400D01*
X286439D01*
X295539Y54500D01*
Y54563D01*
X301046Y60070D01*
X333094D01*
X335811Y57353D01*
Y4522D01*
X334518Y3229D01*
X324872D01*
G02X324485Y4045I0J500D01*
G03X320917I-1784J1455D01*
G02X320530Y3229I-387J-316D01*
G01X308441D01*
G02X308208Y4171I0J500D01*
G03X298092I-5058J9609D01*
G02X297859Y3229I-233J-442D01*
G01X222988D01*
G02X222492Y3795I0J500D01*
G37*
G36*
G01X537402Y3004D02*
G02X536469Y3937I0J933D01*
G01Y71063D01*
G03X534762Y75621I-6941J-1D01*
G01X534701Y75692D01*
Y76359D01*
X534777Y76432D01*
G03X534701Y81827I-2572J2662D01*
G01Y83312D01*
X556961Y105572D01*
Y230387D01*
X556442Y230906D01*
Y230954D01*
X538023Y249374D01*
X537974D01*
X537763Y249585D01*
X333608D01*
X316965Y232942D01*
X282336D01*
X282098Y232704D01*
X282097D01*
X277472Y228078D01*
G02X276626Y228439I-346J361D01*
G01Y252756D01*
G02X277559Y253689I933J0D01*
G01X528363D01*
X528360Y253692D01*
X561024D01*
G02X561960Y252756I0J-936D01*
G01Y226962D01*
X561957D01*
Y3937D01*
G02X561024Y3004I-933J0D01*
G01X537402D01*
G37*
G36*
G01X346119Y39419D02*
X344381Y41157D01*
Y70682D01*
X347203Y73504D01*
Y88581D01*
G03Y91687I-1561J1553D01*
G01Y107231D01*
X350024Y110052D01*
X366301D01*
X370977Y105376D01*
Y40830D01*
X369566Y39419D01*
X366335D01*
G03X363165I-1585J-1669D01*
G01X346119D01*
G37*
%LPC*%
G75*
G36*
G01X188977Y50246D02*
G02X193946Y45276I-1J-4970D01*
G01Y43307D01*
G02X188977Y38338I-4970J1D01*
G01X82677D01*
G02X77708Y43307I0J4969D01*
G01Y45276D01*
G02X82677Y50246I4970J0D01*
G01X188977D01*
G37*
G36*
G01X91283Y52702D02*
G03X90527Y52683I-370J-337D01*
G02Y56373I-2240J1845D01*
G03X91283Y56354I386J318D01*
G02X93287Y57240I2005J-1826D01*
G01X98287D01*
G02X100291Y56354I-1J-2712D01*
G03X101047Y56373I370J337D01*
G02X105527I2240J-1845D01*
G03X106283Y56354I386J318D01*
G02X108287Y57240I2005J-1826D01*
G01X113287D01*
G02X115291Y56354I-1J-2712D01*
G03X116047Y56373I370J337D01*
G02Y52683I2240J-1845D01*
G03X115291Y52702I-386J-318D01*
G02X113287Y51816I-2005J1826D01*
G01X108287D01*
G02X106283Y52702I1J2712D01*
G03X105527Y52683I-370J-337D01*
G02X101047I-2240J1845D01*
G03X100291Y52702I-386J-318D01*
G02X98287Y51816I-2005J1826D01*
G01X93287D01*
G02X91283Y52702I1J2712D01*
G37*
G36*
G01X126062Y21251D02*
G02X122912I-1575J1813D01*
G02X118936Y23064I-1575J1813D01*
G01Y23864D01*
G02X122912Y25677I2401J0D01*
G02X126062I1575J-1813D01*
G02X129212I1575J-1813D01*
G02X132362I1575J-1813D01*
G02X135512I1575J-1813D01*
G02X138662I1575J-1813D01*
G02X142638Y23864I1575J-1813D01*
G01Y23064D01*
G02X138662Y21251I-2401J0D01*
G02X135512I-1575J1813D01*
G02X132362I-1575J1813D01*
G02X129212I-1575J1813D01*
G02X126062I-1575J1813D01*
G37*
G36*
G01X91283Y8213D02*
G03X90527Y8194I-370J-337D01*
G02Y11884I-2240J1845D01*
G03X91283Y11865I386J318D01*
G02X93287Y12750I2004J-1826D01*
G01X98287D01*
G02X100291Y11865I0J-2711D01*
G03X101047Y11884I370J337D01*
G02X105527I2240J-1845D01*
G03X106283Y11865I386J318D01*
G02X108287Y12750I2004J-1826D01*
G01X113287D01*
G02X115291Y11865I0J-2711D01*
G03X116047Y11884I370J337D01*
G02Y8194I2240J-1845D01*
G03X115291Y8213I-386J-318D01*
G02X113287Y7328I-2004J1826D01*
G01X108287D01*
G02X106283Y8213I0J2711D01*
G03X105527Y8194I-370J-337D01*
G02X101047I-2240J1845D01*
G03X100291Y8213I-386J-318D01*
G02X98287Y7328I-2004J1826D01*
G01X93287D01*
G02X91283Y8213I0J2711D01*
G37*
G36*
G01X293572Y104686D02*
G02Y111888I0J3601D01*
G01X297372D01*
G02Y104686I0J-3601D01*
G01X293572D01*
G37*
G36*
G01Y61970D02*
G02Y69172I0J3601D01*
G01X297372D01*
G02Y61970I0J-3601D01*
G01X293572D01*
G37*
G36*
G01X522164Y224586D02*
G03X521511Y224576I-321J-384D01*
G02X518294Y227862I-1530J1720D01*
G03X518301Y228536I-366J341D01*
G02X521677Y231665I1716J1534D01*
G03X522032Y231659I180J173D01*
G02X525384Y228509I1610J-1646D01*
G03Y227856I379J-327D01*
G02X522164Y224586I-1742J-1505D01*
G37*
G36*
G01X417106Y214952D02*
G02X413956I-1575J1813D01*
G02X409980Y216765I-1575J1813D01*
G01Y217565D01*
G02X413956Y219378I2401J0D01*
G02X417106I1575J-1813D01*
G02X420256I1575J-1813D01*
G02X423406I1575J-1813D01*
G02X426556I1575J-1813D01*
G02X429706I1575J-1813D01*
G02X433682Y217565I1575J-1813D01*
G01Y216765D01*
G02X429706Y214952I-2401J0D01*
G02X426556I-1575J1813D01*
G02X423406I-1575J1813D01*
G02X420256I-1575J1813D01*
G02X417106I-1575J1813D01*
G37*
G36*
G01X299319Y193552D02*
G03Y193198I176J-177D01*
G02X296077I-1621J-1635D01*
G03Y193552I-176J177D01*
G02X296232Y196961I1621J1634D01*
G03X296257Y197710I-319J386D01*
G02X296083Y200868I1583J1671D01*
G03X296076Y201521I-382J322D01*
G02X297928Y205340I1729J1520D01*
G03X298454Y205860I27J499D01*
G02X300631Y203657I2300J96D01*
G03X300105Y203137I-27J-499D01*
G02X299562Y201554I-2300J-96D01*
G03X299569Y200901I382J-322D01*
G02X299306Y197607I-1729J-1519D01*
G03X299281Y196858I319J-386D01*
G02X299319Y193552I-1583J-1671D01*
G37*
G36*
G01X301669Y166485D02*
G03X302022Y166476I181J173D01*
G02X301931Y163215I1578J-1676D01*
G03X301578Y163224I-181J-173D01*
G02X301669Y166485I-1578J1676D01*
G37*
G36*
G01X286419Y151052D02*
G03Y150698I176J-177D01*
G02X283177I-1621J-1635D01*
G03Y151052I-176J177D01*
G02X283332Y154461I1621J1634D01*
G03X283357Y155210I-319J386D01*
G02X283183Y158368I1583J1671D01*
G03X283176Y159021I-382J322D01*
G02X286662Y159054I1729J1520D01*
G03X286669Y158401I382J-322D01*
G02X286406Y155107I-1729J-1519D01*
G03X286381Y154358I319J-386D01*
G02X286419Y151052I-1583J-1671D01*
G37*
G36*
G01X304963Y143197D02*
G03X305088Y142537I426J-261D01*
G02X301737Y141903I-1388J-1837D01*
G03X301612Y142563I-426J261D01*
G02X301433Y142713I1387J1837D01*
G03X300773Y142731I-340J-366D01*
G02X300867Y146187I-1473J1769D01*
G03X301527Y146169I340J366D01*
G02X304963Y143197I1473J-1769D01*
G37*
G36*
G01X333081Y185540D02*
X349067Y201526D01*
X376392D01*
G03X376824Y202278I0J500D01*
G02X381571Y205585I2507J1462D01*
G03X382327Y205566I386J318D01*
G02X384331Y206452I2005J-1826D01*
G01X389331D01*
G02X391335Y205566I-1J-2712D01*
G03X392091Y205585I370J337D01*
G02X396571I2240J-1845D01*
G03X397327Y205566I386J318D01*
G02X399331Y206452I2005J-1826D01*
G01X404331D01*
G02X406335Y205566I-1J-2712D01*
G03X407091Y205585I370J337D01*
G02X411838Y202278I2240J-1845D01*
G03X412270Y201526I432J-252D01*
G01X431392D01*
G03X431824Y202278I0J500D01*
G02X436464Y205708I2507J1462D01*
G03X437198I367J339D01*
G02X441464I2133J-1968D01*
G03X442198I367J339D01*
G02X446464I2133J-1968D01*
G03X447198I367J339D01*
G02X451464I2133J-1968D01*
G03X452198I367J339D01*
G02X456464I2133J-1968D01*
G03X457198I367J339D01*
G02X461464I2133J-1968D01*
G03X462198I367J339D01*
G02X466464I2133J-1968D01*
G03X467198I367J339D01*
G02X471464I2133J-1968D01*
G03X472198I367J339D01*
G02X476464I2133J-1968D01*
G03X477198I367J339D01*
G02X481464I2133J-1968D01*
G03X482198I367J339D01*
G02X486464I2133J-1968D01*
G03X487198I367J339D01*
G02X491464I2133J-1968D01*
G03X492198I367J339D01*
G02X495427Y206427I2133J-1968D01*
G03X496116Y206890I189J463D01*
G01Y210146D01*
X497875Y211906D01*
X510534D01*
X511968Y210471D01*
G03X512760Y210585I353J354D01*
G02X518710Y211609I3381J-1845D01*
G03X519474Y211727I334J373D01*
G02Y205753I5032J-2987D01*
G03X518710Y205871I-430J-255D01*
G02X513245Y206200I-2570J2869D01*
G03X512370Y205871I-375J-330D01*
G01Y145861D01*
G03X513245Y145532I500J1D01*
G02X518710Y145861I2895J-2540D01*
G03X519474Y145979I334J373D01*
G02Y140005I5032J-2987D01*
G03X518710Y140123I-430J-255D01*
G02X513245Y140452I-2570J2869D01*
G03X512370Y140123I-375J-330D01*
G01Y138085D01*
X508989Y134704D01*
X317919D01*
X312884Y139740D01*
Y172307D01*
X315812Y175236D01*
X322776D01*
X329960Y182419D01*
X329892Y182576D01*
G02X332924Y185608I2108J924D01*
G01X333081Y185540D01*
G37*
G36*
G01X303700Y131948D02*
G03X303684Y131291I369J-338D01*
G02X300213Y131373I-1771J-1470D01*
G03X300229Y132030I-369J338D01*
G02X303700Y131948I1771J1470D01*
G37*
G36*
G01X281015Y119195D02*
G03X281027Y118487I359J-348D01*
G02X277922Y118436I-1527J-1587D01*
G03X277910Y119144I-359J348D01*
G02X281015Y119195I1527J1587D01*
G37*
G36*
G01X329404Y99204D02*
X325403D01*
G02X323796Y100007I1J2011D01*
G03X323034Y100052I-400J-300D01*
G02X323279Y102782I-1594J1519D01*
G03X324037Y102690I418J275D01*
G02X325404Y103226I1367J-1475D01*
G01X329404D01*
G02X330010Y103133I1J-2011D01*
G03X330654Y103523I151J477D01*
G02X330792Y103992I2168J-383D01*
G03X330331Y104686I-461J194D01*
G01X328690D01*
G02Y111888I0J3601D01*
G01X332490D01*
G02X334559Y105339I0J-3601D01*
G03X334472Y104599I287J-409D01*
G02X331783Y101198I-1649J-1460D01*
G01X331728Y101228D01*
X331416D01*
Y101107D01*
X331404Y101000D01*
G02X329404Y99204I-2000J216D01*
G37*
G36*
G01X340295Y90385D02*
G03X339692Y90104I-144J-479D01*
G02X338234Y93104I-2022J872D01*
G03X338862Y93588I128J483D01*
G01Y96312D01*
G02X338863Y96331I2007J-96D01*
G03X338565Y96578I-250J2D01*
G02X340346Y98807I-420J2162D01*
G03X340851Y98322I500J15D01*
G02X342886Y96321I23J-2011D01*
G01Y92203D01*
X342874Y92096D01*
G02X340295Y90385I-2000J215D01*
G37*
G36*
G01X206357Y80388D02*
G03X205643I-357J-350D01*
G02X202388Y83643I-1643J1612D01*
G03Y84357I-350J357D01*
G02X202685Y87890I1612J1643D01*
G03X202788Y88615I-285J410D01*
G02X205926Y91678I1712J1385D01*
G03X206574I324J381D01*
G02X209540Y88426I1426J-1678D01*
G03X209553Y87700I350J-357D01*
G02X209612Y84357I-1553J-1699D01*
G03Y83643I350J-357D01*
G02X206357Y80388I-1612J-1643D01*
G37*
G36*
G01X328381Y81771D02*
G03X328362Y81011I315J-388D01*
G02X325615Y81165I-1470J-1640D01*
G03X325681Y81923I-290J407D01*
G02X325102Y83334I1433J1412D01*
G01Y87335D01*
G02X325589Y88645I2012J-2D01*
G03X325551Y89336I-379J326D01*
G02X328613Y89384I1506J1607D01*
G03X328597Y88693I353J-354D01*
G02X329126Y87344I-1483J-1360D01*
G01Y83226D01*
X329114Y83119D01*
G02X328381Y81771I-2000J214D01*
G37*
G36*
G01X250522Y78732D02*
G03X250532Y78053I372J-334D01*
G02X247118Y74966I-1666J-1589D01*
G03X246380Y74989I-380J-326D01*
G02X243088Y78208I-1653J1602D01*
G03X243114Y78882I-356J351D01*
G02X246530Y81965I1757J1487D01*
G03X247233Y81948I360J347D01*
G02X250522Y78732I1578J-1676D01*
G37*
G36*
G01X282107Y63242D02*
G03X282774Y63235I337J369D01*
G02X282740Y59805I1518J-1730D01*
G03X282073Y59812I-337J-369D01*
G02X282107Y63242I-1518J1730D01*
G37*
G36*
G01X478834Y227805D02*
G02X477242Y229461I-2234J-555D01*
G03X477867Y230061I140J480D01*
G02X481767Y232205I2234J555D01*
G03X482119Y232196I181J173D01*
G02X482034Y228933I1581J-1674D01*
G03X481682Y228942I-181J-173D01*
G02X479459Y228405I-1581J1674D01*
G03X478834Y227805I-140J-480D01*
G37*
G36*
G01X316143Y186888D02*
G02X313460Y190554I-1643J1612D01*
G03Y191446I-225J446D01*
G02Y195554I1040J2054D01*
G03Y196446I-225J446D01*
G02Y200554I1040J2054D01*
G03Y201446I-225J446D01*
G02X316143Y205112I1040J2054D01*
G03X316857I357J350D01*
G02X319540Y201446I1643J-1612D01*
G03Y200554I225J-446D01*
G02Y196446I-1040J-2054D01*
G03Y195554I225J-446D01*
G02Y191446I-1040J-2054D01*
G03Y190554I225J-446D01*
G02X316857Y186888I-1040J-2054D01*
G03X316143I-357J-350D01*
G37*
G36*
G01X215069Y82515D02*
G02X215026Y84567I-1969J985D01*
G03X215911Y84585I438J242D01*
G02X215954Y82533I1969J-985D01*
G03X215069Y82515I-438J-242D01*
G37*
G36*
G01X245357Y45888D02*
G03X244643I-357J-350D01*
G02Y49112I-1643J1612D01*
G03X245357I357J350D01*
G02Y45888I1643J-1612D01*
G37*
G36*
G01X260300Y36848D02*
G03X259948I-176J-177D01*
G02X256590Y39995I-1624J1632D01*
G03X256575Y40669I-376J329D01*
G02X259864Y43891I1665J1590D01*
G03X260216I176J177D01*
G02X263574Y40744I1624J-1632D01*
G03X263589Y40070I376J-329D01*
G02X260300Y36848I-1665J-1590D01*
G37*
G36*
G01X217179Y39859D02*
G03X217844Y39468I494J79D01*
G02X216437Y36986I756J-2068D01*
G03X215761Y37356I-491J-94D01*
G02X213536Y37644I-854J2138D01*
G03X213186Y37592I-149J-201D01*
G02X209859Y37198I-1849J1371D01*
G03X209206Y37188I-321J-384D01*
G02X209153Y40672I-1531J1719D01*
G03X209806Y40682I321J384D01*
G02X212707Y40813I1531J-1719D01*
G03X213057Y40865I149J201D01*
G02X217179Y39859I1849J-1371D01*
G37*
G36*
G01X244857Y25388D02*
G03X244143I-357J-350D01*
G02Y28612I-1643J1612D01*
G03X244857I357J350D01*
G02Y25388I1643J-1612D01*
G37*
G36*
G01X227666Y17908D02*
G03X228430Y18026I334J373D01*
G02Y12052I5032J-2987D01*
G03X227666Y12170I-430J-255D01*
G02Y17908I-2569J2869D01*
G37*
G54D21*
X60928Y64173D03*
X75100Y36700D03*
X74635Y29153D03*
X76804Y61699D03*
X293146Y81023D03*
X293141Y97997D03*
X313617Y81023D03*
X308208Y101945D03*
X303734Y89882D03*
X309250Y127439D03*
X310500Y184328D03*
X222206Y41500D03*
X268045Y8270D03*
X258088Y21787D03*
X273551Y37112D03*
X322100Y26600D03*
X303900Y28900D03*
X313900Y27200D03*
X315166Y52172D03*
X324700Y16300D03*
X329962Y56703D03*
G54D22*
X312657Y66142D03*
Y107716D03*
G54D20*
X63713Y48425D03*
X65006Y43434D03*
X289800Y165000D03*
X315048Y133300D03*
X309500Y145000D03*
X304000Y213000D03*
X314454Y213250D03*
X326423Y183632D03*
X326000Y217500D03*
X281221Y33971D03*
X286638Y33917D03*
X321373Y56703D03*
X332666Y27700D03*
X332778Y20000D03*
G54D23*
X484960Y86811D03*
X496771D03*
X508583D03*
X520394D03*
G54D18*
X17715Y44095D03*
X525590Y240944D03*
X552795Y40157D03*
G54D19*
X68112Y15039D03*
Y59528D03*
X359156Y208740D03*
%LPD*%
G75*
G36*
G01X318417Y135906D02*
X314085Y140238D01*
Y171809D01*
X316310Y174034D01*
X323274D01*
X330780Y181540D01*
X330942Y181456D01*
G03X333955Y184715I1058J2044D01*
G01X349565Y200325D01*
X495919D01*
X497274Y201680D01*
X497450Y201530D01*
G03X501464Y201772I1881J2210D01*
G02X502198I367J-339D01*
G03Y205708I2133J1968D01*
G02X501464I-367J339D01*
G03X498039Y206339I-2133J-1968D01*
G02X497317Y206786I-222J448D01*
G01Y209648D01*
X498373Y210704D01*
X510036D01*
X511168Y209572D01*
Y138583D01*
X508491Y135906D01*
X507341D01*
G02X506898Y136639I-1J500D01*
G03X502198Y139960I-2567J1353D01*
G02X501464I-367J339D01*
G03X497198I-2133J-1968D01*
G02X496464I-367J339D01*
G03X492198I-2133J-1968D01*
G02X491464I-367J339D01*
G03X487198I-2133J-1968D01*
G02X486464I-367J339D01*
G03X482198I-2133J-1968D01*
G02X481464I-367J339D01*
G03X477198I-2133J-1968D01*
G02X476464I-367J339D01*
G03X472198I-2133J-1968D01*
G02X471464I-367J339D01*
G03X467198I-2133J-1968D01*
G02X466464I-367J339D01*
G03X462198I-2133J-1968D01*
G02X461464I-367J339D01*
G03X457198I-2133J-1968D01*
G02X456464I-367J339D01*
G03X452198I-2133J-1968D01*
G02X451464I-367J339D01*
G03X447198I-2133J-1968D01*
G02X446464I-367J339D01*
G03X442198I-2133J-1968D01*
G02X441464I-367J339D01*
G03X437198I-2133J-1968D01*
G02X436464I-367J339D01*
G03X431764Y136639I-2133J-1968D01*
G02X431321Y135906I-442J-233D01*
G01X412341D01*
G02X411898Y136639I-1J500D01*
G03X407091Y139837I-2567J1353D01*
G02X406335Y139818I-386J318D01*
G03X404331Y140704I-2005J-1826D01*
G01X399331D01*
G03X397327Y139818I1J-2712D01*
G02X396571Y139837I-370J337D01*
G03X392091I-2240J-1845D01*
G02X391335Y139818I-386J318D01*
G03X389331Y140704I-2005J-1826D01*
G01X384331D01*
G03X382327Y139818I1J-2712D01*
G02X381571Y139837I-370J337D01*
G03X376764Y136639I-2240J-1845D01*
G02X376321Y135906I-442J-233D01*
G01X318417D01*
G37*
%LPC*%
G75*
G36*
G01X377951Y160164D02*
G02X371782Y166334I1J6170D01*
G01Y180114D01*
G02X377952Y186284I6171J-1D01*
G01X484252D01*
G02X490422Y180114I0J-6170D01*
G01Y166334D01*
G02X484252Y160164I-6170J0D01*
G01X377951D01*
G37*
G36*
G01X505352Y165002D02*
G03X504626Y164962I-344J-363D01*
G02X504509Y168062I-1758J1486D01*
G03X505236Y168077I356J351D01*
G02X505352Y165002I1632J-1478D01*
G37*
G36*
G01X339055Y153126D02*
G03X338341I-357J-350D01*
G02X334983Y156273I-1643J1612D01*
G03X334997Y156923I-373J333D01*
G02X335030Y159877I1782J1457D01*
G03Y160528I-380J326D01*
G02X335048Y163541I1749J1496D01*
G03Y164201I-376J330D01*
G02X338422Y167330I1731J1517D01*
G03X339136I357J350D01*
G02X342510Y164201I1643J-1612D01*
G03Y163541I376J-330D01*
G02X342528Y160528I-1731J-1517D01*
G03Y159877I380J-326D01*
G02X342494Y156846I-1749J-1496D01*
G03X342480Y156196I373J-333D01*
G02X339055Y153126I-1781J-1458D01*
G37*
G36*
G01X417106Y149204D02*
G02X413956I-1575J1813D01*
G02X409980Y151017I-1575J1813D01*
G01Y151817D01*
G02X413956Y153630I2401J0D01*
G02X417106I1575J-1813D01*
G02X420256I1575J-1813D01*
G02X423406I1575J-1813D01*
G02X426556I1575J-1813D01*
G02X429706I1575J-1813D01*
G02X433682Y151817I1575J-1813D01*
G01Y151017D01*
G02X429706Y149204I-2401J0D01*
G02X426556I-1575J1813D01*
G02X423406I-1575J1813D01*
G02X420256I-1575J1813D01*
G02X417106I-1575J1813D01*
G37*
G54D21*
X322042Y147196D03*
X336238Y148951D03*
G54D19*
X359156Y142992D03*
%LPD*%
G75*
G54D10*
X15748Y15827D03*
X551181Y242913D03*
G54D11*
X15748Y67008D03*
X303150Y242913D03*
X551181Y13780D03*
G54D12*
X5500Y48299D03*
X7960Y85839D03*
X42701Y5500D03*
X48316Y32530D03*
X44316D03*
Y28681D03*
X48316D03*
X44278Y24717D03*
X48278D03*
X49374Y56390D03*
X45374D03*
X45336Y52426D03*
X49336D03*
X41000Y79500D03*
Y75500D03*
X37000Y79500D03*
Y75500D03*
X49374Y60239D03*
X45374D03*
X27960Y85839D03*
X60469Y79819D03*
X56667Y83351D03*
X60393Y83934D03*
X52667Y83351D03*
X282148Y51376D03*
X282093Y55184D03*
X278462Y51437D03*
X278407Y55245D03*
X281964Y47752D03*
X278278Y47813D03*
X279122Y234213D03*
X282142Y251193D03*
X320332Y160022D03*
X316332D03*
Y164522D03*
X320332D03*
X316332Y155668D03*
X320332D03*
X316438Y151436D03*
X320438D03*
X322142Y251193D03*
X328508Y41629D03*
X328424Y45408D03*
X332508Y41629D03*
X332424Y45408D03*
X332565Y49028D03*
X332614Y52663D03*
X328565Y49028D03*
X328614Y52663D03*
X339000Y193500D03*
X335000D03*
Y203500D03*
X339000D03*
Y198500D03*
X335000D03*
X342142Y251193D03*
X353229Y52810D03*
X349229D03*
X353095Y45538D03*
X353094Y49157D03*
X352971Y41813D03*
X349095Y45538D03*
X349094Y49157D03*
X348971Y41813D03*
X354580Y102351D03*
X350569Y102263D03*
X358824Y108849D03*
X352501Y105640D03*
X350827Y108976D03*
X348696Y105396D03*
X356501Y105640D03*
X354827Y108976D03*
X362142Y251193D03*
X382142D03*
X402142D03*
X422142D03*
X442142D03*
X462142D03*
X502142D03*
X482142D03*
X522142D03*
X538965Y41992D03*
Y61992D03*
X559461Y68512D03*
Y88512D03*
Y108512D03*
Y148512D03*
Y128512D03*
Y168512D03*
Y188512D03*
Y208512D03*
G54D13*
X88287Y10039D03*
Y54528D03*
X118287Y10039D03*
X103287D03*
X118287Y54528D03*
X103287D03*
X163287Y10039D03*
X158287D03*
X163287Y54528D03*
X158287D03*
X168287Y10039D03*
Y54528D03*
X208287Y10039D03*
X198287D03*
X208287Y54528D03*
X198287D03*
X213287Y10039D03*
Y54528D03*
X504331Y137992D03*
X499331D03*
X504331Y203740D03*
X499331D03*
G54D14*
G01X-139981Y-146685D02*
G02I-12000J0D01*
G01X-145131D02*
G02I-6850J0D01*
G01X-135981D02*
X-167981D01*
G01X-135981Y-162685D02*
Y-242685D01*
G01D02*
X971619D01*
G01X-135981Y-198185D02*
X971619D01*
G01X-151981Y-162685D02*
Y-130685D01*
G01X-135981Y-162685D02*
X971619D01*
G01X88287Y10039D02*
Y13191D01*
G01X85135Y10039D02*
X88287D01*
G01X220310Y4087D02*
X73567D01*
G01X88287Y51376D02*
Y54528D01*
G01D02*
Y57680D01*
G01X85135Y54528D02*
X88287D01*
G01X103287Y10039D02*
Y13191D01*
G01Y10039D02*
X104700Y13248D01*
G01X103287Y51376D02*
Y54528D01*
G01D02*
Y57680D01*
G01X118287Y10039D02*
Y13191D01*
G01Y10039D02*
X121439D01*
G01X121337Y20412D02*
Y23464D01*
G01D02*
Y26516D01*
G01X118685Y23464D02*
X121337D01*
G01X140237Y20412D02*
Y23464D01*
G01D02*
Y26516D01*
G01Y23464D02*
X142889D01*
G01X118287Y51376D02*
Y54528D01*
G01D02*
Y57680D01*
G01Y54528D02*
X121439D01*
G01X121337Y64901D02*
Y67953D01*
G01X118685Y64901D02*
X121337Y67953D01*
G01X140237Y64901D02*
Y67953D01*
G01D02*
X142889Y64901D01*
G01X158287Y10039D02*
Y13191D01*
G01X155808Y7560D02*
X158287Y10039D01*
G01X163287D02*
Y13191D01*
G01X160808Y7560D02*
X163287Y10039D01*
G01X158287Y51376D02*
Y54528D01*
G01D02*
Y57680D01*
G01X163287Y51376D02*
Y54528D01*
G01D02*
Y57680D01*
G01X184119Y-162685D02*
Y-242685D01*
G01X168287Y10039D02*
Y13191D01*
G01X165808Y7560D02*
X168287Y10039D01*
G01Y51376D02*
Y54528D01*
G01D02*
Y57680D01*
G01X198287Y10039D02*
Y13191D01*
G01X195808Y7560D02*
X198287Y10039D01*
G01X208287D02*
Y13191D01*
G01X205808Y7560D02*
X208287Y10039D01*
G01X198287Y51376D02*
Y54528D01*
G01X195808Y52049D02*
X198287Y54528D01*
G01X208287Y51376D02*
Y54528D01*
G01D02*
Y57680D01*
G01X213287Y10039D02*
Y13191D01*
G01Y10039D02*
X216439D01*
G01X213287Y51376D02*
Y54528D01*
G01D02*
Y57680D01*
G01Y54528D02*
X216439D01*
G01X321619Y-162685D02*
Y-242685D01*
G01X436619Y-162685D02*
Y-242685D01*
G01X499331Y137992D02*
Y141144D01*
G01Y137992D02*
X501810Y140471D01*
G01X499331Y200588D02*
Y203740D01*
G01D02*
Y206892D01*
G01X520394Y81809D02*
Y86811D01*
G01D02*
Y91813D01*
G01X515392Y86811D02*
X520394D01*
G01D02*
X525396D01*
G01X504331Y137992D02*
Y141144D01*
G01Y137992D02*
X507483D01*
G01X504331Y200588D02*
Y203740D01*
G01D02*
Y206892D01*
G01Y203740D02*
X507483D01*
G01X604119Y-162685D02*
Y-242685D01*
G01X774119Y-162685D02*
Y-242685D01*
G01X971619Y-162685D02*
Y-242685D01*
G01X999619Y-146685D02*
G02I-12000J0D01*
G01X1003619D02*
X971619D01*
G01X994469D02*
G02I-6850J0D01*
G01X987619Y-162685D02*
Y-130685D01*
X73567Y4087D03*
X220310D03*
G54D15*
X140237Y23464D03*
X121337D03*
X140237Y67953D03*
X121337D03*
G54D16*
X520394Y86811D03*
G54D17*
G01X-116181Y-215185D02*
Y-232685D01*
G01X-121203Y-215185D02*
X-111159D01*
G01X-103048Y-232685D02*
Y-215185D01*
X-97808D01*
X-96061Y-216060D01*
X-94751Y-218102D01*
X-94314Y-220435D01*
X-94751Y-222768D01*
X-95843Y-224518D01*
X-97808Y-225394D01*
X-103048D01*
G01X-58878Y-216644D02*
X-60188Y-215768D01*
X-61716Y-215185D01*
X-63463D01*
X-65428Y-216060D01*
X-66956Y-217518D01*
X-68048Y-219269D01*
X-68921Y-222185D01*
X-69140Y-224810D01*
X-68703Y-227435D01*
X-68048Y-229185D01*
X-66738Y-230935D01*
X-65209Y-232102D01*
X-63681Y-232685D01*
X-62153D01*
X-60624Y-232102D01*
X-59314Y-231227D01*
X-58222Y-230061D01*
G01X-49893Y-232685D02*
Y-215185D01*
G01Y-223643D02*
X-48801Y-222185D01*
X-47709Y-221310D01*
X-45963Y-221019D01*
X-44653Y-221310D01*
X-43124Y-222477D01*
X-42469Y-224227D01*
Y-232685D01*
G01X-24751D02*
Y-221019D01*
G01Y-223060D02*
X-25624Y-221894D01*
X-26935Y-221310D01*
X-28463Y-221019D01*
X-29991Y-221602D01*
X-31301Y-222768D01*
X-32175Y-224518D01*
X-32611Y-226852D01*
X-32175Y-229185D01*
X-31301Y-230935D01*
X-29991Y-232102D01*
X-28463Y-232685D01*
X-26935Y-232393D01*
X-25624Y-231519D01*
X-24751Y-230352D01*
G01X-14893Y-232685D02*
Y-221019D01*
G01Y-223935D02*
X-14019Y-222477D01*
X-12709Y-221310D01*
X-10963Y-221019D01*
X-9435Y-221310D01*
X-8124Y-222477D01*
X-7469Y-224518D01*
Y-232685D01*
G01X2607D02*
Y-221019D01*
G01Y-223935D02*
X3481Y-222477D01*
X4791Y-221310D01*
X6537Y-221019D01*
X8065Y-221310D01*
X9376Y-222477D01*
X10031Y-224518D01*
Y-232685D01*
G01X20544Y-224810D02*
X27531D01*
X26876Y-222768D01*
X25784Y-221602D01*
X24256Y-221019D01*
X22727Y-221310D01*
X21417Y-222185D01*
X20544Y-224227D01*
X20107Y-225977D01*
Y-227727D01*
X20544Y-229477D01*
X21636Y-231227D01*
X22946Y-232393D01*
X24474Y-232685D01*
X26002Y-232102D01*
X27531Y-230352D01*
G01X41319Y-232685D02*
Y-215185D01*
G01X71734Y-232685D02*
Y-215185D01*
G01X80904D02*
Y-232685D01*
G01Y-223935D02*
X71734D01*
G01X89016Y-232685D02*
Y-215185D01*
X93382D01*
X95129Y-216060D01*
X96439Y-217227D01*
X97531Y-218976D01*
X98404Y-221019D01*
X98622Y-223935D01*
X98404Y-226852D01*
X97531Y-228894D01*
X96439Y-230644D01*
X95129Y-231810D01*
X93382Y-232685D01*
X89016D01*
G01X106516D02*
Y-215185D01*
X110882D01*
X112629Y-216060D01*
X113939Y-217227D01*
X115031Y-218976D01*
X115904Y-221019D01*
X116122Y-223935D01*
X115904Y-226852D01*
X115031Y-228894D01*
X113939Y-230644D01*
X112629Y-231810D01*
X110882Y-232685D01*
X106516D01*
G01X148065Y-223352D02*
X148939Y-222477D01*
X149594Y-221019D01*
X150031Y-218976D01*
X149594Y-217227D01*
X148721Y-216060D01*
X147192Y-215185D01*
X141297D01*
Y-232685D01*
X148502D01*
X150031Y-231519D01*
X150904Y-229768D01*
X151341Y-227727D01*
X150904Y-225685D01*
X149594Y-223935D01*
X148065Y-223352D01*
X141297D01*
G01X159452Y-232685D02*
Y-215185D01*
X164692D01*
X166439Y-216060D01*
X167749Y-218102D01*
X168186Y-220435D01*
X167749Y-222768D01*
X166657Y-224518D01*
X164692Y-225394D01*
X159452D01*
G01X-16858Y-187685D02*
Y-170185D01*
X-11181Y-184768D01*
X-5504Y-170185D01*
Y-187685D01*
G01X6319D02*
X5009Y-187393D01*
X3699Y-186227D01*
X2825Y-184185D01*
X2389Y-181852D01*
X2825Y-179518D01*
X3699Y-177477D01*
X5009Y-176310D01*
X6319Y-176019D01*
X7629Y-176310D01*
X8939Y-177477D01*
X9812Y-179518D01*
X10031Y-181852D01*
X9812Y-184185D01*
X8939Y-186227D01*
X7629Y-187393D01*
X6319Y-187685D01*
G01X27749Y-170185D02*
Y-187685D01*
G01Y-185061D02*
X26876Y-186519D01*
X25565Y-187393D01*
X24037Y-187685D01*
X22291Y-187102D01*
X20981Y-185644D01*
X20107Y-183894D01*
X19889Y-181852D01*
X20107Y-179810D01*
X20981Y-178060D01*
X22291Y-176602D01*
X24037Y-176019D01*
X25565Y-176310D01*
X26657Y-176894D01*
X27749Y-178060D01*
G01X38044Y-179810D02*
X45031D01*
X44376Y-177768D01*
X43284Y-176602D01*
X41756Y-176019D01*
X40227Y-176310D01*
X38917Y-177185D01*
X38044Y-179227D01*
X37607Y-180977D01*
Y-182727D01*
X38044Y-184477D01*
X39136Y-186227D01*
X40446Y-187393D01*
X41974Y-187685D01*
X43502Y-187102D01*
X45031Y-185352D01*
G01X58819Y-187685D02*
Y-170185D01*
G01X204702Y-187685D02*
Y-170185D01*
X209942D01*
X211689Y-171060D01*
X212999Y-173102D01*
X213436Y-175435D01*
X212999Y-177768D01*
X211907Y-179518D01*
X209942Y-180394D01*
X204702D01*
G01X231372Y-171644D02*
X230062Y-170768D01*
X228534Y-170185D01*
X226787D01*
X224822Y-171060D01*
X223294Y-172518D01*
X222202Y-174269D01*
X221329Y-177185D01*
X221110Y-179810D01*
X221547Y-182435D01*
X222202Y-184185D01*
X223512Y-185935D01*
X225041Y-187102D01*
X226569Y-187685D01*
X228097D01*
X229626Y-187102D01*
X230936Y-186227D01*
X232028Y-185061D01*
G01X245815Y-178352D02*
X246689Y-177477D01*
X247344Y-176019D01*
X247781Y-173976D01*
X247344Y-172227D01*
X246471Y-171060D01*
X244942Y-170185D01*
X239047D01*
Y-187685D01*
X246252D01*
X247781Y-186519D01*
X248654Y-184768D01*
X249091Y-182727D01*
X248654Y-180685D01*
X247344Y-178935D01*
X245815Y-178352D01*
X239047D01*
G01X255019Y-193518D02*
X268119D01*
G01X274047Y-187685D02*
Y-170185D01*
X284091Y-187685D01*
Y-170185D01*
G01X296569Y-187685D02*
X294822Y-187393D01*
X293294Y-186227D01*
X291984Y-184477D01*
X291110Y-182435D01*
X290674Y-180102D01*
Y-177768D01*
X291110Y-175435D01*
X291984Y-173393D01*
X293294Y-171644D01*
X294822Y-170477D01*
X296569Y-170185D01*
X298315Y-170477D01*
X299844Y-171644D01*
X301154Y-173393D01*
X302028Y-175435D01*
X302464Y-177768D01*
Y-180102D01*
X302028Y-182435D01*
X301154Y-184477D01*
X299844Y-186227D01*
X298315Y-187393D01*
X296569Y-187685D01*
G01X217819Y-232685D02*
Y-215185D01*
X215199Y-218685D01*
G01Y-232685D02*
X220439D01*
G01X234882D02*
X235319Y-228894D01*
X235974Y-225685D01*
X236847Y-222768D01*
X237939Y-219560D01*
X239686Y-215185D01*
X230952D01*
G01X248016Y-229185D02*
X249325Y-231227D01*
X251072Y-232393D01*
X253037Y-232685D01*
X254784Y-232393D01*
X256531Y-230935D01*
X257622Y-229185D01*
X257841Y-227435D01*
X257404Y-225394D01*
X255876Y-223935D01*
X254347Y-223352D01*
X252382D01*
G01X254347D02*
X255657Y-222477D01*
X256749Y-221019D01*
X257186Y-219269D01*
X256749Y-217518D01*
X255657Y-216060D01*
X253692Y-215185D01*
X251727Y-215477D01*
X249762Y-216644D01*
G01X270319Y-215185D02*
X268572Y-215768D01*
X267262Y-217227D01*
X266389Y-218976D01*
X265734Y-221310D01*
X265516Y-223935D01*
X265734Y-226560D01*
X266389Y-228894D01*
X267262Y-230644D01*
X268572Y-232102D01*
X270319Y-232685D01*
X272065Y-232102D01*
X273376Y-230644D01*
X274249Y-228894D01*
X274904Y-226560D01*
X275122Y-223935D01*
X274904Y-221310D01*
X274249Y-218976D01*
X273376Y-217227D01*
X272065Y-215768D01*
X270319Y-215185D01*
G01X287819Y-232685D02*
Y-215185D01*
X285199Y-218685D01*
G01Y-232685D02*
X290439D01*
G01X365784Y-230352D02*
X367531Y-231810D01*
X369496Y-232685D01*
X371242D01*
X372989Y-231810D01*
X374299Y-230352D01*
X374954Y-228310D01*
X374517Y-226269D01*
X373426Y-224518D01*
X371461Y-223352D01*
X368841Y-222768D01*
X367312Y-221602D01*
X366657Y-219560D01*
X367094Y-217518D01*
X368186Y-216060D01*
X369714Y-215185D01*
X371242D01*
X372771Y-215768D01*
X374081Y-217227D01*
G01X382410Y-232685D02*
X387869Y-215185D01*
X393328Y-232685D01*
G01X391362Y-226560D02*
X384375D01*
G01X347410Y-170185D02*
X352869Y-187685D01*
X358328Y-170185D01*
G01X374736Y-187685D02*
X366002D01*
Y-170185D01*
X374736D01*
G01X371242Y-178643D02*
X366002D01*
G01X383502Y-187685D02*
Y-170185D01*
X388961D01*
X390707Y-171060D01*
X391799Y-172227D01*
X392236Y-174560D01*
X391799Y-176894D01*
X390489Y-178352D01*
X388961Y-179227D01*
X383502D01*
G01X388961D02*
X392236Y-187685D01*
G01X405369Y-188268D02*
X404932Y-187977D01*
Y-187393D01*
X405369Y-187102D01*
X405806Y-187393D01*
Y-187977D01*
X405369Y-188268D01*
G01X480952Y-170185D02*
Y-187685D01*
X489686D01*
G01X506749D02*
Y-176019D01*
G01Y-178060D02*
X505876Y-176894D01*
X504565Y-176310D01*
X503037Y-176019D01*
X501509Y-176602D01*
X500199Y-177768D01*
X499325Y-179518D01*
X498889Y-181852D01*
X499325Y-184185D01*
X500199Y-185935D01*
X501509Y-187102D01*
X503037Y-187685D01*
X504565Y-187393D01*
X505876Y-186519D01*
X506749Y-185352D01*
G01X515734Y-192935D02*
X517044Y-193518D01*
X518791Y-192935D01*
X519882Y-191769D01*
X520756Y-190310D01*
X522065Y-185644D01*
X524904Y-176019D01*
G01X517917D02*
X522065Y-185644D01*
G01X534544Y-179810D02*
X541531D01*
X540876Y-177768D01*
X539784Y-176602D01*
X538256Y-176019D01*
X536727Y-176310D01*
X535417Y-177185D01*
X534544Y-179227D01*
X534107Y-180977D01*
Y-182727D01*
X534544Y-184477D01*
X535636Y-186227D01*
X536946Y-187393D01*
X538474Y-187685D01*
X540002Y-187102D01*
X541531Y-185352D01*
G01X552262Y-187685D02*
Y-176019D01*
G01Y-178352D02*
X553354Y-177185D01*
X554446Y-176310D01*
X555974Y-176019D01*
X557065Y-176310D01*
X558376Y-177185D01*
G01X533436Y-215185D02*
Y-232685D01*
X524702D01*
G01X508949D02*
Y-215185D01*
X517028Y-227727D01*
X506110D01*
G01X623066Y-187685D02*
Y-170185D01*
X627432D01*
X629179Y-171060D01*
X630489Y-172227D01*
X631581Y-173976D01*
X632454Y-176019D01*
X632672Y-178935D01*
X632454Y-181852D01*
X631581Y-183894D01*
X630489Y-185644D01*
X629179Y-186810D01*
X627432Y-187685D01*
X623066D01*
G01X642094Y-179810D02*
X649081D01*
X648426Y-177768D01*
X647334Y-176602D01*
X645806Y-176019D01*
X644277Y-176310D01*
X642967Y-177185D01*
X642094Y-179227D01*
X641657Y-180977D01*
Y-182727D01*
X642094Y-184477D01*
X643186Y-186227D01*
X644496Y-187393D01*
X646024Y-187685D01*
X647552Y-187102D01*
X649081Y-185352D01*
G01X659594Y-185644D02*
X660686Y-186810D01*
X662214Y-187685D01*
X663524D01*
X664834Y-187102D01*
X665707Y-186227D01*
X666144Y-185061D01*
X665926Y-183310D01*
X665052Y-182435D01*
X661122Y-180685D01*
X660249Y-178643D01*
X660686Y-177185D01*
X661559Y-176310D01*
X662869Y-176019D01*
X664179Y-176310D01*
X665489Y-177185D01*
G01X680369Y-176019D02*
Y-187685D01*
G01Y-171352D02*
X679932Y-171060D01*
Y-170477D01*
X680369Y-170185D01*
X680806Y-170477D01*
Y-171060D01*
X680369Y-171352D01*
G01X694812Y-192060D02*
X696341Y-193227D01*
X698087Y-193518D01*
X699615Y-193227D01*
X700926Y-191769D01*
X701799Y-189727D01*
Y-176019D01*
G01Y-178352D02*
X700926Y-177185D01*
X699615Y-176310D01*
X698087Y-176019D01*
X696341Y-176602D01*
X695249Y-177768D01*
X694375Y-179810D01*
X693939Y-181852D01*
X694157Y-183602D01*
X695031Y-185644D01*
X696341Y-187102D01*
X698087Y-187685D01*
X699397Y-187393D01*
X700926Y-186227D01*
X701799Y-185061D01*
G01X711657Y-187685D02*
Y-176019D01*
G01Y-178935D02*
X712531Y-177477D01*
X713841Y-176310D01*
X715587Y-176019D01*
X717115Y-176310D01*
X718426Y-177477D01*
X719081Y-179518D01*
Y-187685D01*
G01X729594Y-179810D02*
X736581D01*
X735926Y-177768D01*
X734834Y-176602D01*
X733306Y-176019D01*
X731777Y-176310D01*
X730467Y-177185D01*
X729594Y-179227D01*
X729157Y-180977D01*
Y-182727D01*
X729594Y-184477D01*
X730686Y-186227D01*
X731996Y-187393D01*
X733524Y-187685D01*
X735052Y-187102D01*
X736581Y-185352D01*
G01X747312Y-187685D02*
Y-176019D01*
G01Y-178352D02*
X748404Y-177185D01*
X749496Y-176310D01*
X751024Y-176019D01*
X752115Y-176310D01*
X753426Y-177185D01*
G01X664179Y-223935D02*
X668546D01*
Y-229185D01*
X667236Y-230935D01*
X665707Y-232102D01*
X663524Y-232685D01*
X661341Y-232102D01*
X659812Y-230935D01*
X658502Y-229185D01*
X657629Y-227143D01*
X657192Y-224810D01*
Y-222768D01*
X657629Y-221019D01*
X658502Y-218976D01*
X659812Y-217227D01*
X661122Y-216060D01*
X662869Y-215185D01*
X664397D01*
X666144Y-215768D01*
X667454Y-216935D01*
G01X684736Y-232685D02*
X676002D01*
Y-215185D01*
X684736D01*
G01X681242Y-223643D02*
X676002D01*
G01X693502Y-215185D02*
Y-232685D01*
X702236D01*
G01X715369D02*
X713622Y-232393D01*
X712094Y-231227D01*
X710784Y-229477D01*
X709910Y-227435D01*
X709474Y-225102D01*
Y-222768D01*
X709910Y-220435D01*
X710784Y-218393D01*
X712094Y-216644D01*
X713622Y-215477D01*
X715369Y-215185D01*
X717115Y-215477D01*
X718644Y-216644D01*
X719954Y-218393D01*
X720828Y-220435D01*
X721264Y-222768D01*
Y-225102D01*
X720828Y-227435D01*
X719954Y-229477D01*
X718644Y-231227D01*
X717115Y-232393D01*
X715369Y-232685D01*
G01X794069Y-215185D02*
X792322Y-215768D01*
X791012Y-217227D01*
X790139Y-218976D01*
X789484Y-221310D01*
X789266Y-223935D01*
X789484Y-226560D01*
X790139Y-228894D01*
X791012Y-230644D01*
X792322Y-232102D01*
X794069Y-232685D01*
X795815Y-232102D01*
X797126Y-230644D01*
X797999Y-228894D01*
X798654Y-226560D01*
X798872Y-223935D01*
X798654Y-221310D01*
X797999Y-218976D01*
X797126Y-217227D01*
X795815Y-215768D01*
X794069Y-215185D01*
G01X807421Y-225394D02*
X808949Y-223352D01*
X810259Y-222185D01*
X812006Y-221602D01*
X813534Y-222185D01*
X814626Y-223352D01*
X815499Y-225102D01*
X815717Y-227143D01*
X815499Y-228894D01*
X814626Y-230644D01*
X813315Y-232102D01*
X811787Y-232685D01*
X810041Y-232102D01*
X808512Y-230352D01*
X807639Y-227727D01*
X807421Y-224810D01*
X807857Y-221019D01*
X808512Y-218976D01*
X809604Y-216935D01*
X811132Y-215477D01*
X812661Y-215185D01*
X814189Y-215768D01*
X815281Y-217227D01*
G01X825139Y-233268D02*
X832999Y-215185D01*
G01X842421Y-218102D02*
X843731Y-216352D01*
X845259Y-215477D01*
X847006Y-215185D01*
X849189Y-215768D01*
X850717Y-217227D01*
X851154Y-218976D01*
X850936Y-220727D01*
X850062Y-222185D01*
X845696Y-225102D01*
X843731Y-227143D01*
X842421Y-230061D01*
X841984Y-232685D01*
X851154D01*
G01X859921Y-218102D02*
X861231Y-216352D01*
X862759Y-215477D01*
X864506Y-215185D01*
X866689Y-215768D01*
X868217Y-217227D01*
X868654Y-218976D01*
X868436Y-220727D01*
X867562Y-222185D01*
X863196Y-225102D01*
X861231Y-227143D01*
X859921Y-230061D01*
X859484Y-232685D01*
X868654D01*
G01X877639Y-233268D02*
X885499Y-215185D01*
G01X894921Y-218102D02*
X896231Y-216352D01*
X897759Y-215477D01*
X899506Y-215185D01*
X901689Y-215768D01*
X903217Y-217227D01*
X903654Y-218976D01*
X903436Y-220727D01*
X902562Y-222185D01*
X898196Y-225102D01*
X896231Y-227143D01*
X894921Y-230061D01*
X894484Y-232685D01*
X903654D01*
G01X916569Y-215185D02*
X914822Y-215768D01*
X913512Y-217227D01*
X912639Y-218976D01*
X911984Y-221310D01*
X911766Y-223935D01*
X911984Y-226560D01*
X912639Y-228894D01*
X913512Y-230644D01*
X914822Y-232102D01*
X916569Y-232685D01*
X918315Y-232102D01*
X919626Y-230644D01*
X920499Y-228894D01*
X921154Y-226560D01*
X921372Y-223935D01*
X921154Y-221310D01*
X920499Y-218976D01*
X919626Y-217227D01*
X918315Y-215768D01*
X916569Y-215185D01*
G01X934069Y-232685D02*
Y-215185D01*
X931449Y-218685D01*
G01Y-232685D02*
X936689D01*
G01X951132D02*
X951569Y-228894D01*
X952224Y-225685D01*
X953097Y-222768D01*
X954189Y-219560D01*
X955936Y-215185D01*
X947202D01*
G01X841766Y-187685D02*
Y-170185D01*
X846132D01*
X847879Y-171060D01*
X849189Y-172227D01*
X850281Y-173976D01*
X851154Y-176019D01*
X851372Y-178935D01*
X851154Y-181852D01*
X850281Y-183894D01*
X849189Y-185644D01*
X847879Y-186810D01*
X846132Y-187685D01*
X841766D01*
G01X867999D02*
Y-176019D01*
G01Y-178060D02*
X867126Y-176894D01*
X865815Y-176310D01*
X864287Y-176019D01*
X862759Y-176602D01*
X861449Y-177768D01*
X860575Y-179518D01*
X860139Y-181852D01*
X860575Y-184185D01*
X861449Y-185935D01*
X862759Y-187102D01*
X864287Y-187685D01*
X865815Y-187393D01*
X867126Y-186519D01*
X867999Y-185352D01*
G01X881569Y-170185D02*
Y-187685D01*
G01X878512Y-176019D02*
X884626D01*
G01X895794Y-179810D02*
X902781D01*
X902126Y-177768D01*
X901034Y-176602D01*
X899506Y-176019D01*
X897977Y-176310D01*
X896667Y-177185D01*
X895794Y-179227D01*
X895357Y-180977D01*
Y-182727D01*
X895794Y-184477D01*
X896886Y-186227D01*
X898196Y-187393D01*
X899724Y-187685D01*
X901252Y-187102D01*
X902781Y-185352D01*
M02*
